(kicad_pcb
	(version 20240108)
	(generator "pcbnew")
	(generator_version "8.0")
	(general
		(thickness 1.62)
		(legacy_teardrops no)
	)
	(paper "A4")
	(title_block
		(title "Jetson Orin Baseboard")
		(date "2025-03-12")
		(rev "1.3.4")
		(company "Antmicro Ltd")
		(comment 1 "www.antmicro.com")
		(comment 9 "footprints 277-280 of 677")
	)
	(layers
		(0 "F.Cu" signal)
		(1 "In1.Cu" signal)
		(2 "In2.Cu" signal)
		(3 "In3.Cu" signal)
		(4 "In4.Cu" jumper)
		(5 "In5.Cu" signal)
		(6 "In6.Cu" signal)
		(31 "B.Cu" signal)
		(32 "B.Adhes" user "B.Adhesive")
		(33 "F.Adhes" user "F.Adhesive")
		(34 "B.Paste" user)
		(35 "F.Paste" user)
		(36 "B.SilkS" user "B.Silkscreen")
		(37 "F.SilkS" user "F.Silkscreen")
		(38 "B.Mask" user)
		(39 "F.Mask" user)
		(40 "Dwgs.User" user "User.Drawings")
		(41 "Cmts.User" user "User.Comments")
		(42 "Eco1.User" user "User.Eco1")
		(43 "Eco2.User" user "User.Eco2")
		(44 "Edge.Cuts" user)
		(45 "Margin" user)
		(46 "B.CrtYd" user "B.Courtyard")
		(47 "F.CrtYd" user "F.Courtyard")
		(48 "B.Fab" user)
		(49 "F.Fab" user)
	)
	(footprint "antmicro-footprints:C_0402_1005Metric"
		(layer "F.Cu")
		(at 71.7 103.35 90)
		(descr "Capacitor SMD 0402")
		(tags "capacitor SMD 0402")
		(property "Reference" "C54"
			(at 0.8 0.45 90)
			(layer "F.SilkS")
			(effects
				(font
					(size 0.7 0.7)
					(thickness 0.15)
				)
				(justify left bottom)
			)
		)
		(property "Value" "C_100n_0402"
			(at 0 1.4 90)
			(layer "F.Fab")
			(effects
				(font
					(size 0.7 0.7)
					(thickness 0.15)
				)
				(justify left bottom)
			)
		)
		(property "Footprint" "antmicro-footprints:C_0402_1005Metric"
			(at 0 0 90)
			(layer "F.Fab")
			(hide yes)
			(effects
				(font
					(size 1.27 1.27)
					(thickness 0.15)
				)
			)
		)
		(property "Datasheet" "https://www.murata.com/products/productdetail?partno=GRM155R61H104KE14%23"
			(at 0 0 90)
			(layer "F.Fab")
			(hide yes)
			(effects
				(font
					(size 1.27 1.27)
					(thickness 0.15)
				)
			)
		)
		(property "Author" "Antmicro"
			(at 175.05 31.65 0)
			(layer "F.Fab")
			(hide yes)
			(effects
				(font
					(size 1 1)
					(thickness 0.15)
				)
			)
		)
		(property "Dielectric" "X5R"
			(at 175.05 31.65 0)
			(layer "F.Fab")
			(hide yes)
			(effects
				(font
					(size 1 1)
					(thickness 0.15)
				)
			)
		)
		(property "License" "Apache-2.0"
			(at 175.05 31.65 0)
			(layer "F.Fab")
			(hide yes)
			(effects
				(font
					(size 1 1)
					(thickness 0.15)
				)
			)
		)
		(property "MPN" "GRM155R61H104KE14D"
			(at 175.05 31.65 0)
			(layer "F.Fab")
			(hide yes)
			(effects
				(font
					(size 1 1)
					(thickness 0.15)
				)
			)
		)
		(property "Manufacturer" "Murata"
			(at 175.05 31.65 0)
			(layer "F.Fab")
			(hide yes)
			(effects
				(font
					(size 1 1)
					(thickness 0.15)
				)
			)
		)
		(property "Val" "100n"
			(at 175.05 31.65 0)
			(layer "F.Fab")
			(hide yes)
			(effects
				(font
					(size 1 1)
					(thickness 0.15)
				)
			)
		)
		(property "Voltage" "50V"
			(at 175.05 31.65 0)
			(layer "F.Fab")
			(hide yes)
			(effects
				(font
					(size 1 1)
					(thickness 0.15)
				)
			)
		)
		(sheetname "USB Debug, DP")
		(sheetfile "usb.kicad_sch")
		(attr smd)
		(fp_rect
			(start -0.925 -0.47)
			(end 0.925 0.47)
			(stroke
				(width 0.05)
				(type default)
			)
			(fill none)
			(layer "F.CrtYd")
		)
		(fp_line
			(start 0.504 -0.25)
			(end 0.504 0.248)
			(stroke
				(width 0.15)
				(type solid)
			)
			(layer "F.Fab")
		)
		(fp_line
			(start -0.494 -0.25)
			(end 0.504 -0.25)
			(stroke
				(width 0.15)
				(type solid)
			)
			(layer "F.Fab")
		)
		(fp_line
			(start 0.504 0.248)
			(end -0.494 0.248)
			(stroke
				(width 0.15)
				(type solid)
			)
			(layer "F.Fab")
		)
		(fp_line
			(start -0.494 0.248)
			(end -0.494 -0.25)
			(stroke
				(width 0.15)
				(type solid)
			)
			(layer "F.Fab")
		)
		(fp_text user "License: Apache-2.0"
			(at -0.932 5.17 90)
			(layer "F.Fab")
			(hide yes)
			(effects
				(font
					(size 0.7 0.7)
					(thickness 0.15)
				)
				(justify left bottom)
			)
		)
		(fp_text user "Author: Antmicro"
			(at -0.932 4.17 90)
			(layer "F.Fab")
			(hide yes)
			(effects
				(font
					(size 0.7 0.7)
					(thickness 0.15)
				)
				(justify left bottom)
			)
		)
		(fp_text user "${REFERENCE}"
			(at -0.932 3.168 90)
			(layer "F.Fab")
			(hide yes)
			(effects
				(font
					(size 0.7 0.7)
					(thickness 0.15)
				)
				(justify left bottom)
			)
		)
		(pad "1" smd roundrect
			(at -0.48 0 90)
			(size 0.59 0.64)
			(layers "F.Cu" "F.Paste" "F.Mask")
			(roundrect_rratio 0.25)
			(net 87 "+3V3")
			(pintype "passive")
		)
		(pad "2" smd roundrect
			(at 0.48 0 90)
			(size 0.59 0.64)
			(layers "F.Cu" "F.Paste" "F.Mask")
			(roundrect_rratio 0.25)
			(net 1 "GND")
			(pintype "passive")
		)
	)
	(footprint "antmicro-footprints:USON-10_2.5x1mm_P0.5mm"
		(layer "F.Cu")
		(at 75 115.5 90)
		(descr "USON-10 2.5x1mm_ Pitch 0.5mm")
		(tags "USON-10 2.5x1mm Pitch 0.5mm")
		(property "Reference" "U16"
			(at -1.66 -1.01 180)
			(layer "F.SilkS")
			(effects
				(font
					(size 0.7 0.7)
					(thickness 0.15)
				)
				(justify left bottom)
			)
		)
		(property "Value" "TPD4E05U06QDQARQ1"
			(at 0.018 2.499 90)
			(layer "F.Fab")
			(effects
				(font
					(size 0.7 0.7)
					(thickness 0.15)
				)
				(justify left bottom)
			)
		)
		(property "Footprint" "antmicro-footprints:USON-10_2.5x1mm_P0.5mm"
			(at 0 0 90)
			(layer "F.Fab")
			(hide yes)
			(effects
				(font
					(size 1.27 1.27)
					(thickness 0.15)
				)
			)
		)
		(property "Datasheet" "https://www.ti.com/lit/ds/symlink/tpd4e05u06-q1.pdf?HQS=dis-mous-null-mousermode-dsf-pf-null-wwe&ts=1663591265741&ref_url=https%253A%252F%252Fwww.mouser.com%252F"
			(at 0 0 90)
			(layer "F.Fab")
			(hide yes)
			(effects
				(font
					(size 1.27 1.27)
					(thickness 0.15)
				)
			)
		)
		(property "Author" "Antmicro"
			(at 190.5 40.5 0)
			(layer "F.Fab")
			(hide yes)
			(effects
				(font
					(size 1 1)
					(thickness 0.15)
				)
			)
		)
		(property "License" "Apache-2.0"
			(at 190.5 40.5 0)
			(layer "F.Fab")
			(hide yes)
			(effects
				(font
					(size 1 1)
					(thickness 0.15)
				)
			)
		)
		(property "MPN" "TPD4E05U06QDQARQ1"
			(at 190.5 40.5 0)
			(layer "F.Fab")
			(hide yes)
			(effects
				(font
					(size 1 1)
					(thickness 0.15)
				)
			)
		)
		(property "Manufacturer" "Texas Instruments"
			(at 190.5 40.5 0)
			(layer "F.Fab")
			(hide yes)
			(effects
				(font
					(size 1 1)
					(thickness 0.15)
				)
			)
		)
		(sheetname "USB Debug, DP")
		(sheetfile "usb.kicad_sch")
		(attr smd)
		(fp_line
			(start 0.498 -1.401)
			(end -0.5 -1.401)
			(stroke
				(width 0.15)
				(type solid)
			)
			(layer "F.SilkS")
		)
		(fp_line
			(start 0.498 1.398)
			(end -0.5 1.398)
			(stroke
				(width 0.15)
				(type solid)
			)
			(layer "F.SilkS")
		)
		(fp_circle
			(center -0.68 -1.27)
			(end -0.63 -1.27)
			(stroke
				(width 0.15)
				(type solid)
			)
			(fill solid)
			(layer "F.SilkS")
		)
		(fp_rect
			(start -0.8 -1.5)
			(end 0.8 1.499)
			(stroke
				(width 0.05)
				(type solid)
			)
			(fill none)
			(layer "F.CrtYd")
		)
		(fp_line
			(start 0.498 -1.25)
			(end -0.25 -1.25)
			(stroke
				(width 0.15)
				(type solid)
			)
			(layer "F.Fab")
		)
		(fp_line
			(start 0.498 -1.25)
			(end 0.498 1.249)
			(stroke
				(width 0.15)
				(type solid)
			)
			(layer "F.Fab")
		)
		(fp_line
			(start -0.25 -1.25)
			(end -0.5 -1)
			(stroke
				(width 0.15)
				(type solid)
			)
			(layer "F.Fab")
		)
		(fp_line
			(start -0.5 -1)
			(end -0.5 1.249)
			(stroke
				(width 0.15)
				(type solid)
			)
			(layer "F.Fab")
		)
		(fp_line
			(start -0.5 1.249)
			(end 0.498 1.249)
			(stroke
				(width 0.15)
				(type solid)
			)
			(layer "F.Fab")
		)
		(fp_text user "${REFERENCE}"
			(at -0.802 4.498 90)
			(layer "F.Fab")
			(hide yes)
			(effects
				(font
					(size 0.7 0.7)
					(thickness 0.15)
				)
				(justify left bottom)
			)
		)
		(fp_text user "License: Apache-2.0"
			(at -0.802 6.9 90)
			(layer "F.Fab")
			(hide yes)
			(effects
				(font
					(size 0.7 0.7)
					(thickness 0.15)
				)
				(justify left bottom)
			)
		)
		(fp_text user "Author: Antmicro"
			(at -0.802 5.7 90)
			(layer "F.Fab")
			(hide yes)
			(effects
				(font
					(size 0.7 0.7)
					(thickness 0.15)
				)
				(justify left bottom)
			)
		)
		(pad "1" smd roundrect
			(at -0.387 -1)
			(size 0.25 0.55)
			(layers "F.Cu" "F.Paste" "F.Mask")
			(roundrect_rratio 0.25)
			(net 277 "/USB Debug, DP/USBC0_CC1")
			(pintype "passive")
		)
		(pad "2" smd roundrect
			(at -0.387 -0.5)
			(size 0.25 0.55)
			(layers "F.Cu" "F.Paste" "F.Mask")
			(roundrect_rratio 0.25)
			(net 439 "USB2_D_P")
			(pintype "passive")
		)
		(pad "3" smd roundrect
			(at -0.387 0)
			(size 0.4 0.55)
			(layers "F.Cu" "F.Paste" "F.Mask")
			(roundrect_rratio 0.25)
			(net 1 "GND")
			(pintype "power_in")
		)
		(pad "4" smd roundrect
			(at -0.387 0.498)
			(size 0.25 0.55)
			(layers "F.Cu" "F.Paste" "F.Mask")
			(roundrect_rratio 0.25)
			(net 437 "USB2_D_N")
			(pintype "passive")
		)
		(pad "5" smd roundrect
			(at -0.387 0.998)
			(size 0.25 0.55)
			(layers "F.Cu" "F.Paste" "F.Mask")
			(roundrect_rratio 0.25)
			(net 278 "/USB Debug, DP/USBC0_CC2")
			(pintype "passive")
		)
		(pad "6" smd roundrect
			(at 0.385 0.998)
			(size 0.25 0.55)
			(layers "F.Cu" "F.Paste" "F.Mask")
			(roundrect_rratio 0.25)
			(net 278 "/USB Debug, DP/USBC0_CC2")
			(pintype "passive")
		)
		(pad "7" smd roundrect
			(at 0.385 0.498)
			(size 0.25 0.55)
			(layers "F.Cu" "F.Paste" "F.Mask")
			(roundrect_rratio 0.25)
			(net 437 "USB2_D_N")
			(pintype "passive")
		)
		(pad "8" smd roundrect
			(at 0.385 0)
			(size 0.4 0.55)
			(layers "F.Cu" "F.Paste" "F.Mask")
			(roundrect_rratio 0.25)
			(net 1 "GND")
			(pintype "passive")
		)
		(pad "9" smd roundrect
			(at 0.385 -0.5)
			(size 0.25 0.55)
			(layers "F.Cu" "F.Paste" "F.Mask")
			(roundrect_rratio 0.25)
			(net 439 "USB2_D_P")
			(pintype "passive")
		)
		(pad "10" smd roundrect
			(at 0.385 -1)
			(size 0.25 0.55)
			(layers "F.Cu" "F.Paste" "F.Mask")
			(roundrect_rratio 0.25)
			(net 277 "/USB Debug, DP/USBC0_CC1")
			(pintype "passive")
		)
	)
	(footprint "antmicro-footprints:C_0402_1005Metric"
		(layer "F.Cu")
		(at 73.6 111 -90)
		(descr "Capacitor SMD 0402")
		(tags "capacitor SMD 0402")
		(property "Reference" "C60"
			(at 2.95 -0.4 -90)
			(layer "F.SilkS")
			(effects
				(font
					(size 0.7 0.7)
					(thickness 0.15)
				)
				(justify left bottom)
			)
		)
		(property "Value" "C_100n_0402"
			(at 0 1.4 -90)
			(layer "F.Fab")
			(effects
				(font
					(size 0.7 0.7)
					(thickness 0.15)
				)
				(justify left bottom)
			)
		)
		(property "Footprint" "antmicro-footprints:C_0402_1005Metric"
			(at 0 0 -90)
			(layer "F.Fab")
			(hide yes)
			(effects
				(font
					(size 1.27 1.27)
					(thickness 0.15)
				)
			)
		)
		(property "Datasheet" "https://www.murata.com/products/productdetail?partno=GRM155R61H104KE14%23"
			(at 0 0 -90)
			(layer "F.Fab")
			(hide yes)
			(effects
				(font
					(size 1.27 1.27)
					(thickness 0.15)
				)
			)
		)
		(property "Author" "Antmicro"
			(at -37.4 184.6 0)
			(layer "F.Fab")
			(hide yes)
			(effects
				(font
					(size 1 1)
					(thickness 0.15)
				)
			)
		)
		(property "Dielectric" "X5R"
			(at -37.4 184.6 0)
			(layer "F.Fab")
			(hide yes)
			(effects
				(font
					(size 1 1)
					(thickness 0.15)
				)
			)
		)
		(property "License" "Apache-2.0"
			(at -37.4 184.6 0)
			(layer "F.Fab")
			(hide yes)
			(effects
				(font
					(size 1 1)
					(thickness 0.15)
				)
			)
		)
		(property "MPN" "GRM155R61H104KE14D"
			(at -37.4 184.6 0)
			(layer "F.Fab")
			(hide yes)
			(effects
				(font
					(size 1 1)
					(thickness 0.15)
				)
			)
		)
		(property "Manufacturer" "Murata"
			(at -37.4 184.6 0)
			(layer "F.Fab")
			(hide yes)
			(effects
				(font
					(size 1 1)
					(thickness 0.15)
				)
			)
		)
		(property "Val" "100n"
			(at -37.4 184.6 0)
			(layer "F.Fab")
			(hide yes)
			(effects
				(font
					(size 1 1)
					(thickness 0.15)
				)
			)
		)
		(property "Voltage" "50V"
			(at -37.4 184.6 0)
			(layer "F.Fab")
			(hide yes)
			(effects
				(font
					(size 1 1)
					(thickness 0.15)
				)
			)
		)
		(sheetname "USB Debug, DP")
		(sheetfile "usb.kicad_sch")
		(attr smd)
		(fp_rect
			(start -0.925 -0.47)
			(end 0.925 0.47)
			(stroke
				(width 0.05)
				(type default)
			)
			(fill none)
			(layer "F.CrtYd")
		)
		(fp_line
			(start -0.494 0.248)
			(end -0.494 -0.25)
			(stroke
				(width 0.15)
				(type solid)
			)
			(layer "F.Fab")
		)
		(fp_line
			(start 0.504 0.248)
			(end -0.494 0.248)
			(stroke
				(width 0.15)
				(type solid)
			)
			(layer "F.Fab")
		)
		(fp_line
			(start -0.494 -0.25)
			(end 0.504 -0.25)
			(stroke
				(width 0.15)
				(type solid)
			)
			(layer "F.Fab")
		)
		(fp_line
			(start 0.504 -0.25)
			(end 0.504 0.248)
			(stroke
				(width 0.15)
				(type solid)
			)
			(layer "F.Fab")
		)
		(fp_text user "Author: Antmicro"
			(at -0.932 4.17 -90)
			(layer "F.Fab")
			(hide yes)
			(effects
				(font
					(size 0.7 0.7)
					(thickness 0.15)
				)
				(justify left bottom)
			)
		)
		(fp_text user "${REFERENCE}"
			(at -0.932 3.168 -90)
			(layer "F.Fab")
			(hide yes)
			(effects
				(font
					(size 0.7 0.7)
					(thickness 0.15)
				)
				(justify left bottom)
			)
		)
		(fp_text user "License: Apache-2.0"
			(at -0.932 5.17 -90)
			(layer "F.Fab")
			(hide yes)
			(effects
				(font
					(size 0.7 0.7)
					(thickness 0.15)
				)
				(justify left bottom)
			)
		)
		(pad "1" smd roundrect
			(at -0.48 0 270)
			(size 0.59 0.64)
			(layers "F.Cu" "F.Paste" "F.Mask")
			(roundrect_rratio 0.25)
			(net 257 "/USB Debug, DP/USBC0_TX1_P")
			(pintype "passive")
		)
		(pad "2" smd roundrect
			(at 0.48 0 270)
			(size 0.59 0.64)
			(layers "F.Cu" "F.Paste" "F.Mask")
			(roundrect_rratio 0.25)
			(net 258 "/USB Debug, DP/USBC0_CONN_TX1_P")
			(pintype "passive")
		)
	)
	(footprint "antmicro-footprints:C_0402_1005Metric"
		(layer "F.Cu")
		(at 117.8 111.75 90)
		(descr "Capacitor SMD 0402")
		(tags "capacitor SMD 0402")
		(property "Reference" "C72"
			(at 0.8 0.35 90)
			(layer "F.SilkS")
			(effects
				(font
					(size 0.7 0.7)
					(thickness 0.15)
				)
				(justify left bottom)
			)
		)
		(property "Value" "C_100n_0402"
			(at 0 1.4 90)
			(layer "F.Fab")
			(effects
				(font
					(size 0.7 0.7)
					(thickness 0.15)
				)
				(justify left bottom)
			)
		)
		(property "Footprint" "antmicro-footprints:C_0402_1005Metric"
			(at 0 0 90)
			(layer "F.Fab")
			(hide yes)
			(effects
				(font
					(size 1.27 1.27)
					(thickness 0.15)
				)
			)
		)
		(property "Datasheet" "https://www.murata.com/products/productdetail?partno=GRM155R61H104KE14%23"
			(at 0 0 90)
			(layer "F.Fab")
			(hide yes)
			(effects
				(font
					(size 1.27 1.27)
					(thickness 0.15)
				)
			)
		)
		(property "Author" "Antmicro"
			(at 229.55 -6.05 0)
			(layer "F.Fab")
			(hide yes)
			(effects
				(font
					(size 1 1)
					(thickness 0.15)
				)
			)
		)
		(property "Dielectric" "X5R"
			(at 229.55 -6.05 0)
			(layer "F.Fab")
			(hide yes)
			(effects
				(font
					(size 1 1)
					(thickness 0.15)
				)
			)
		)
		(property "License" "Apache-2.0"
			(at 229.55 -6.05 0)
			(layer "F.Fab")
			(hide yes)
			(effects
				(font
					(size 1 1)
					(thickness 0.15)
				)
			)
		)
		(property "MPN" "GRM155R61H104KE14D"
			(at 229.55 -6.05 0)
			(layer "F.Fab")
			(hide yes)
			(effects
				(font
					(size 1 1)
					(thickness 0.15)
				)
			)
		)
		(property "Manufacturer" "Murata"
			(at 229.55 -6.05 0)
			(layer "F.Fab")
			(hide yes)
			(effects
				(font
					(size 1 1)
					(thickness 0.15)
				)
			)
		)
		(property "Val" "100n"
			(at 229.55 -6.05 0)
			(layer "F.Fab")
			(hide yes)
			(effects
				(font
					(size 1 1)
					(thickness 0.15)
				)
			)
		)
		(property "Voltage" "50V"
			(at 229.55 -6.05 0)
			(layer "F.Fab")
			(hide yes)
			(effects
				(font
					(size 1 1)
					(thickness 0.15)
				)
			)
		)
		(sheetname "USB3")
		(sheetfile "usb3.kicad_sch")
		(attr smd)
		(fp_rect
			(start -0.925 -0.47)
			(end 0.925 0.47)
			(stroke
				(width 0.05)
				(type default)
			)
			(fill none)
			(layer "F.CrtYd")
		)
		(fp_line
			(start 0.504 -0.25)
			(end 0.504 0.248)
			(stroke
				(width 0.15)
				(type solid)
			)
			(layer "F.Fab")
		)
		(fp_line
			(start -0.494 -0.25)
			(end 0.504 -0.25)
			(stroke
				(width 0.15)
				(type solid)
			)
			(layer "F.Fab")
		)
		(fp_line
			(start 0.504 0.248)
			(end -0.494 0.248)
			(stroke
				(width 0.15)
				(type solid)
			)
			(layer "F.Fab")
		)
		(fp_line
			(start -0.494 0.248)
			(end -0.494 -0.25)
			(stroke
				(width 0.15)
				(type solid)
			)
			(layer "F.Fab")
		)
		(fp_text user "License: Apache-2.0"
			(at -0.932 5.17 90)
			(layer "F.Fab")
			(hide yes)
			(effects
				(font
					(size 0.7 0.7)
					(thickness 0.15)
				)
				(justify left bottom)
			)
		)
		(fp_text user "Author: Antmicro"
			(at -0.932 4.17 90)
			(layer "F.Fab")
			(hide yes)
			(effects
				(font
					(size 0.7 0.7)
					(thickness 0.15)
				)
				(justify left bottom)
			)
		)
		(fp_text user "${REFERENCE}"
			(at -0.932 3.168 90)
			(layer "F.Fab")
			(hide yes)
			(effects
				(font
					(size 0.7 0.7)
					(thickness 0.15)
				)
				(justify left bottom)
			)
		)
		(pad "1" smd roundrect
			(at -0.48 0 90)
			(size 0.59 0.64)
			(layers "F.Cu" "F.Paste" "F.Mask")
			(roundrect_rratio 0.25)
			(net 269 "/USB3/USBC1_CONN_TX2_P")
			(pintype "passive")
		)
		(pad "2" smd roundrect
			(at 0.48 0 90)
			(size 0.59 0.64)
			(layers "F.Cu" "F.Paste" "F.Mask")
			(roundrect_rratio 0.25)
			(net 268 "/USB3/USBC1_TX2_P")
			(pintype "passive")
		)
	)
)
